FILE_TYPE = CONNECTIVITY;
{Allegro Design Entry HDL 17.2-2016 S081 (4005846) 1/11/2022}
"PAGE_NUMBER" = 91;
0"NC";
1"P3V3_AUX\g";
2"P3V3_AUX\g";
3"P12V_S3_AUX_CPU0_NVDIMM\g";
4"P12V_S3_AUX_CPU0_NVDIMM\g";
5"GND\g";
6"GND\g";
7"GND\g";
8"GND\g";
9"GND\g";
10"M_E_CPU0_SA_DQ<31:0>";
11"M_E_CPU0_SA_CB<7:0>";
12"M_E_CPU0_SB_CB<7:0>";
13"M_E_CPU0_SA_CA<6:0>";
14"M_E_CPU0_SB_CA<6:0>";
15"M_E_CPU0_SB_DQ<31:0>";
16"M_E_CPU0_SB_DQS_DP<9:0>";
17"M_E_CPU0_SA_DQS_DP<9:0>";
18"M_E_CPU0_SB_DQS_DN<9:0>";
19"M_E_CPU0_SA_DQS_DN<9:0>";
20"I3C_SPD_DDREFGH_CPU0_LVC1_SCL_R2";
21"PD_CHE_CPU0_DIMM2_SAA";
22"I3C_SPD_DDREFGH_CPU0_LVC1_SDA";
23"M_E_CPU0_ALERT_N";
24"RST_M_EF_CPU0_FPGA_N";
25"I3C_SPD_DDREFGH_CPU0_LVC1_SCL";
26"TP_CHE_CPU0_DIMM2_FRU_4";
27"TP_CHE_CPU0_DIMM2_FRU_5";
28"TP_CHE_CPU0_DIMM2_FRU_6";
29"M_E_CPU0_SB_DQS_DN<4>";
30"M_E_CPU0_SA_DQS_DN<9>";
31"M_E_CPU0_SA_DQS_DN<8>";
32"M_E_CPU0_SA_DQS_DN<7>";
33"M_E_CPU0_SA_DQS_DN<6>";
34"M_E_CPU0_SA_DQS_DN<5>";
35"M_E_CPU0_SA_DQS_DN<3>";
36"M_E_CPU0_SA_DQS_DN<4>";
37"M_E_CPU0_SA_DQS_DN<2>";
38"M_E_CPU0_SA_DQS_DN<1>";
39"M_E_CPU0_SA_DQS_DN<0>";
40"M_E_CPU0_SB_DQS_DN<9>";
41"M_E_CPU0_SB_DQS_DN<7>";
42"M_E_CPU0_SB_DQS_DN<8>";
43"M_E_CPU0_SB_DQS_DN<6>";
44"M_E_CPU0_SB_DQS_DN<5>";
45"M_E_CPU0_SB_DQS_DN<2>";
46"M_E_CPU0_SB_DQS_DN<3>";
47"M_E_CPU0_SB_DQS_DN<1>";
48"M_E_CPU0_SB_DQS_DN<0>";
49"M_E_CPU0_SA_DQS_DP<9>";
50"M_E_CPU0_SA_DQS_DP<8>";
51"M_E_CPU0_SA_DQS_DP<7>";
52"M_E_CPU0_SA_DQS_DP<6>";
53"M_E_CPU0_SA_DQS_DP<5>";
54"M_E_CPU0_SA_DQS_DP<4>";
55"M_E_CPU0_SA_DQS_DP<3>";
56"M_E_CPU0_SA_DQS_DP<2>";
57"M_E_CPU0_SA_DQS_DP<1>";
58"M_E_CPU0_SA_DQS_DP<0>";
59"M_E_CPU0_SB_DQS_DP<9>";
60"M_E_CPU0_SB_DQS_DP<8>";
61"M_E_CPU0_SB_DQS_DP<7>";
62"M_E_CPU0_SB_DQS_DP<6>";
63"M_E_CPU0_SB_DQS_DP<5>";
64"M_E_CPU0_SB_DQS_DP<4>";
65"M_E_CPU0_SB_DQS_DP<3>";
66"M_E_CPU0_SB_DQS_DP<2>";
67"M_E_CPU0_SB_DQS_DP<1>";
68"M_E_CPU0_SB_DQS_DP<0>";
69"PWRGD_CHE_CPU0_DIMM2";
70"M_E_CPU0_SB_DQ<22>";
71"M_E_CPU0_SA_CB<0>";
72"M_E_CPU0_SA_DQ<25>";
73"M_E_CPU0_SA_DQ<4>";
74"M_E_CPU0_SB_DQ<30>";
75"TP_CHE_CPU0_DIMM2_FRU_0";
76"TP_CHE_CPU0_DIMM2_FRU_1";
77"TP_CHE_CPU0_DIMM2_FRU_2";
78"TP_CHE_CPU0_DIMM2_FRU_3";
79"M_E_CPU0_SB_PAR";
80"M_E_CPU0_SA_PAR";
81"M_E_CPU0_SB_RSP<1>";
82"M_E_CPU0_SA_RSP<1>";
83"M_E_CPU0_SB_DQ<0>";
84"M_E_CPU0_SB_DQ<1>";
85"M_E_CPU0_SB_DQ<2>";
86"M_E_CPU0_SB_DQ<3>";
87"M_E_CPU0_SB_DQ<4>";
88"M_E_CPU0_SB_DQ<5>";
89"M_E_CPU0_SB_DQ<6>";
90"M_E_CPU0_SB_DQ<7>";
91"M_E_CPU0_SB_DQ<8>";
92"M_E_CPU0_SB_DQ<9>";
93"M_E_CPU0_SB_DQ<10>";
94"M_E_CPU0_SB_DQ<11>";
95"M_E_CPU0_SB_DQ<12>";
96"M_E_CPU0_SB_DQ<13>";
97"M_E_CPU0_SB_DQ<14>";
98"M_E_CPU0_SB_DQ<15>";
99"M_E_CPU0_SB_DQ<16>";
100"M_E_CPU0_SB_DQ<17>";
101"M_E_CPU0_SB_DQ<18>";
102"M_E_CPU0_SB_DQ<19>";
103"M_E_CPU0_SB_DQ<20>";
104"M_E_CPU0_SB_DQ<21>";
105"M_E_CPU0_SB_DQ<23>";
106"M_E_CPU0_SB_DQ<24>";
107"M_E_CPU0_SB_DQ<25>";
108"M_E_CPU0_SB_DQ<26>";
109"M_E_CPU0_SB_DQ<27>";
110"M_E_CPU0_SB_DQ<28>";
111"M_E_CPU0_SB_DQ<29>";
112"M_E_CPU0_SB_DQ<31>";
113"M_E_CPU0_SA_DQ<0>";
114"M_E_CPU0_SA_DQ<1>";
115"M_E_CPU0_SA_DQ<2>";
116"M_E_CPU0_SA_DQ<3>";
117"M_E_CPU0_SA_DQ<5>";
118"M_E_CPU0_SA_DQ<6>";
119"M_E_CPU0_SA_DQ<7>";
120"M_E_CPU0_SA_DQ<8>";
121"M_E_CPU0_SA_DQ<9>";
122"M_E_CPU0_SA_DQ<10>";
123"M_E_CPU0_SA_DQ<11>";
124"M_E_CPU0_SA_DQ<12>";
125"M_E_CPU0_SA_DQ<13>";
126"M_E_CPU0_SA_DQ<14>";
127"M_E_CPU0_SA_DQ<15>";
128"M_E_CPU0_SA_DQ<16>";
129"M_E_CPU0_SA_DQ<17>";
130"M_E_CPU0_SA_DQ<18>";
131"M_E_CPU0_SA_DQ<19>";
132"M_E_CPU0_SA_DQ<20>";
133"M_E_CPU0_SA_DQ<21>";
134"M_E_CPU0_SA_DQ<22>";
135"M_E_CPU0_SA_DQ<23>";
136"M_E_CPU0_SA_DQ<24>";
137"M_E_CPU0_SA_DQ<26>";
138"M_E_CPU0_SA_DQ<27>";
139"M_E_CPU0_SA_DQ<28>";
140"M_E_CPU0_SA_DQ<29>";
141"M_E_CPU0_SA_DQ<30>";
142"M_E_CPU0_SB_CS_N<3>";
143"M_E_CPU0_SA_CS_N<3>";
144"M_E_CPU0_SB_CS_N<2>";
145"M_E_CPU0_SA_CS_N<2>";
146"M_E_CPU0_CLK_DP<1>";
147"M_E_CPU0_CLK_DN<1>";
148"M_E_CPU0_SB_CB<0>";
149"M_E_CPU0_SB_CB<1>";
150"M_E_CPU0_SB_CB<2>";
151"M_E_CPU0_SB_CB<3>";
152"M_E_CPU0_SB_CB<4>";
153"M_E_CPU0_SB_CB<5>";
154"M_E_CPU0_SB_CB<6>";
155"M_E_CPU0_SA_CB<2>";
156"M_E_CPU0_SA_CB<3>";
157"M_E_CPU0_SA_CB<5>";
158"M_E_CPU0_SA_CB<6>";
159"M_E_CPU0_SB_CA<6>";
160"M_E_CPU0_SA_CA<6>";
161"M_E_CPU0_SB_CA<5>";
162"M_E_CPU0_SA_CA<5>";
163"M_E_CPU0_SB_CA<4>";
164"M_E_CPU0_SA_CA<4>";
165"M_E_CPU0_SB_CA<3>";
166"M_E_CPU0_SA_CA<3>";
167"M_E_CPU0_SB_CA<2>";
168"M_E_CPU0_SA_CA<2>";
169"M_E_CPU0_SB_CA<1>";
170"M_E_CPU0_SA_CA<1>";
171"M_E_CPU0_SB_CA<0>";
172"M_E_CPU0_SA_CA<0>";
173"M_E_CPU0_SB_CB<7>";
174"M_E_CPU0_SA_CB<1>";
175"M_E_CPU0_SA_CB<4>";
176"M_E_CPU0_SA_CB<7>";
177"M_E_CPU0_SA_DQ<31>";
178"PD_CHE_CPU0_DIMM2_SAA";
%"UNIVERSAL_GND"
"1","(-1650,-250)","0","logical_power","I1";
;
CDS_LIB"logical_power"
HDL_POWER"GND";
"A"9;
%"TAP"
"1","(-225,3325)","0","standard","I100";
;
CDS_LIB"standard"
BODY_TYPE"PLUMBING"
HDL_TAP"TRUE";
"B \NAC \NWC"10;
"S \NAC"
BN"15"127;
%"TAP"
"1","(-225,3425)","0","standard","I101";
;
CDS_LIB"standard"
BODY_TYPE"PLUMBING"
HDL_TAP"TRUE";
"B \NAC \NWC"10;
"S \NAC"
BN"17"129;
%"TAP"
"1","(-225,3475)","0","standard","I102";
;
CDS_LIB"standard"
BODY_TYPE"PLUMBING"
HDL_TAP"TRUE";
"B \NAC \NWC"10;
"S \NAC"
BN"18"130;
%"TAP"
"1","(-225,3525)","0","standard","I103";
;
CDS_LIB"standard"
BODY_TYPE"PLUMBING"
HDL_TAP"TRUE";
"B \NAC \NWC"10;
"S \NAC"
BN"19"131;
%"TAP"
"1","(-225,3575)","0","standard","I104";
;
CDS_LIB"standard"
BODY_TYPE"PLUMBING"
HDL_TAP"TRUE";
"B \NAC \NWC"10;
"S \NAC"
BN"20"132;
%"TAP"
"1","(-225,3625)","0","standard","I105";
;
CDS_LIB"standard"
BODY_TYPE"PLUMBING"
HDL_TAP"TRUE";
"B \NAC \NWC"10;
"S \NAC"
BN"21"133;
%"TAP"
"1","(-225,3675)","0","standard","I106";
;
CDS_LIB"standard"
BODY_TYPE"PLUMBING"
HDL_TAP"TRUE";
"B \NAC \NWC"10;
"S \NAC"
BN"22"134;
%"TAP"
"1","(-225,3725)","0","standard","I107";
;
CDS_LIB"standard"
BODY_TYPE"PLUMBING"
HDL_TAP"TRUE";
"B \NAC \NWC"10;
"S \NAC"
BN"23"135;
%"TAP"
"1","(-225,3825)","0","standard","I108";
;
CDS_LIB"standard"
BODY_TYPE"PLUMBING"
HDL_TAP"TRUE";
"B \NAC \NWC"10;
"S \NAC"
BN"25"72;
%"TAP"
"1","(-225,3775)","0","standard","I109";
;
CDS_LIB"standard"
BODY_TYPE"PLUMBING"
HDL_TAP"TRUE";
"B \NAC \NWC"10;
"S \NAC"
BN"24"136;
%"TAP"
"1","(-225,3875)","0","standard","I110";
;
CDS_LIB"standard"
BODY_TYPE"PLUMBING"
HDL_TAP"TRUE";
"B \NAC \NWC"10;
"S \NAC"
BN"26"137;
%"TAP"
"1","(-225,3925)","0","standard","I111";
;
CDS_LIB"standard"
BODY_TYPE"PLUMBING"
HDL_TAP"TRUE";
"B \NAC \NWC"10;
"S \NAC"
BN"27"138;
%"TAP"
"1","(-225,3975)","0","standard","I112";
;
CDS_LIB"standard"
BODY_TYPE"PLUMBING"
HDL_TAP"TRUE";
"B \NAC \NWC"10;
"S \NAC"
BN"28"139;
%"TAP"
"1","(-1875,4075)","2","standard","I114";
;
CDS_LIB"standard"
BODY_TYPE"PLUMBING"
HDL_TAP"TRUE";
"B \NAC \NWC"13;
"S \NAC"
BN"5"162;
%"TAP"
"1","(-1875,4025)","2","standard","I115";
;
CDS_LIB"standard"
BODY_TYPE"PLUMBING"
HDL_TAP"TRUE";
"B \NAC \NWC"13;
"S \NAC"
BN"4"164;
%"TAP"
"1","(-1875,4125)","2","standard","I116";
;
CDS_LIB"standard"
BODY_TYPE"PLUMBING"
HDL_TAP"TRUE";
"B \NAC \NWC"13;
"S \NAC"
BN"6"160;
%"TAP"
"1","(-225,4125)","0","standard","I117";
;
CDS_LIB"standard"
BODY_TYPE"PLUMBING"
HDL_TAP"TRUE";
"B \NAC \NWC"10;
"S \NAC"
BN"31"177;
%"TAP"
"1","(-225,4075)","0","standard","I118";
;
CDS_LIB"standard"
BODY_TYPE"PLUMBING"
HDL_TAP"TRUE";
"B \NAC \NWC"10;
"S \NAC"
BN"30"141;
%"TAP"
"1","(-225,4025)","0","standard","I119";
;
CDS_LIB"standard"
BODY_TYPE"PLUMBING"
HDL_TAP"TRUE";
"B \NAC \NWC"10;
"S \NAC"
BN"29"140;
%"VCC_CORE"
"1","(-2700,2000)","0","logical_power","I12";
;
HDL_POWER"P3V3_AUX"
CDS_LIB"logical_power";
"A"2;
%"UNIVERSAL_GND"
"1","(1500,-125)","0","logical_power","I120";
;
CDS_LIB"logical_power"
HDL_POWER"GND";
"A"8;
%"UNIVERSAL_GND"
"1","(3125,-125)","0","logical_power","I121";
;
CDS_LIB"logical_power"
HDL_POWER"GND";
"A"7;
%"VCC_CORE"
"1","(1500,575)","0","logical_power","I122";
;
HDL_POWER"P3V3_AUX"
CDS_LIB"logical_power";
"A"1;
%"Q_CAP"
"1","(1500,250)","0","pure_quanta","I123";
;
PART_NUMBER"CH5221MEB00"
VALUE"2.2UF"
VOLTAGE"6.3V"
TOLERANCE"20%"
PACK_TYPE"C0402"
MATERIAL"X6S"
$LOCATION"C29"
CDS_LIB"pure_quanta"
CDS_LOCATION"C29"
$SEC"1"
CDS_SEC"1";
"B"
$PN"2"8;
"A"
$PN"1"1;
%"Q_CAP"
"1","(2500,250)","0","pure_quanta","I124";
;
PART_NUMBER"CH6103KEA00"
PACK_TYPE"C0805"
TOLERANCE"10%"
VALUE"10UF"
VOLTAGE"16V"
MATERIAL"X6S"
$LOCATION"C30"
CDS_LIB"pure_quanta"
CDS_LOCATION"C30"
$SEC"1"
CDS_SEC"1";
"B"
$PN"2"7;
"A"
$PN"1"4;
%"VCC_CORE"
"1","(2500,575)","0","logical_power","I125";
;
HDL_POWER"P12V_S3_AUX_CPU0_NVDIMM"
CDS_LIB"logical_power";
"A"4;
%"TAP"
"1","(2525,2175)","0","standard","I128";
;
CDS_LIB"standard"
BODY_TYPE"PLUMBING"
HDL_TAP"TRUE";
"B \NAC \NWC"16;
"S \NAC"
BN"0"68;
%"TAP"
"1","(2525,2275)","0","standard","I129";
;
CDS_LIB"standard"
BODY_TYPE"PLUMBING"
HDL_TAP"TRUE";
"B \NAC \NWC"16;
"S \NAC"
BN"1"67;
%"SCONN288_ADR50017P087CC"
"1","(-1050,2400)","0","pure_quanta","I13";
;
PART_NUMBER"DFHST8FS460"
MATERIAL"IO"
PART_TYPE"SMLF"
VALUE"SCONN288_ADR50017-P087CC"
$LOCATION"J10"
NEEDS_NO_SIZE"TRUE"
CDS_LMAN_SYM_OUTLINE"-450,1875,450,-1875"
CDS_LIB"pure_quanta"
CDS_LOCATION"J10"
$SEC"1"
CDS_SEC"1";
"DQ31_A"
$PN"194"177;
"CB7_A"
$PN"205"176;
"CB4_A"
$PN"58"175;
"CB1_A"
$PN"53"174;
"CB7_B"
$PN"236"173;
"ALERT_N \B"
$PN"62"23;
"CA0_A"
$PN"66"172;
"CA0_B"
$PN"76"171;
"CA1_A"
$PN"211"170;
"CA1_B"
$PN"221"169;
"CA2_A"
$PN"68"168;
"CA2_B"
$PN"78"167;
"CA3_A"
$PN"213"166;
"CA3_B"
$PN"223"165;
"CA4_A"
$PN"70"164;
"CA4_B"
$PN"80"163;
"CA5_A"
$PN"215"162;
"CA5_B"
$PN"225"161;
"CA6_A"
$PN"72"160;
"CA6_B"
$PN"82"159;
"CB6_A"
$PN"203"158;
"CB5_A"
$PN"60"157;
"CB3_A"
$PN"198"156;
"CB2_A"
$PN"196"155;
"CB0_A"
$PN"51"71;
"CB6_B"
$PN"234"154;
"CB5_B"
$PN"91"153;
"CB4_B"
$PN"89"152;
"CB3_B"
$PN"243"151;
"CB2_B"
$PN"241"150;
"CB1_B"
$PN"98"149;
"CB0_B"
$PN"96"148;
"CK_C \B"
$PN"218"147;
"CK_T"
$PN"217"146;
"CS0_A_N"
$PN"64"145;
"CS0_B_N"
$PN"84"144;
"CS1_A_N"
$PN"209"143;
"CS1_B_N"
$PN"229"142;
"DQ30_A"
$PN"192"141;
"DQ29_A"
$PN"49"140;
"DQ28_A"
$PN"47"139;
"DQ27_A"
$PN"187"138;
"DQ26_A"
$PN"185"137;
"DQ25_A"
$PN"42"72;
"DQ24_A"
$PN"40"136;
"DQ23_A"
$PN"183"135;
"DQ22_A"
$PN"181"134;
"DQ21_A"
$PN"38"133;
"DQ20_A"
$PN"36"132;
"DQ19_A"
$PN"176"131;
"DQ18_A"
$PN"174"130;
"DQ17_A"
$PN"31"129;
"DQ16_A"
$PN"29"128;
"DQ15_A"
$PN"172"127;
"DQ14_A"
$PN"170"126;
"DQ13_A"
$PN"27"125;
"DQ12_A"
$PN"25"124;
"DQ11_A"
$PN"165"123;
"DQ10_A"
$PN"163"122;
"DQ9_A"
$PN"20"121;
"DQ8_A"
$PN"18"120;
"DQ7_A"
$PN"161"119;
"DQ6_A"
$PN"159"118;
"DQ5_A"
$PN"16"117;
"DQ4_A"
$PN"14"73;
"DQ3_A"
$PN"154"116;
"DQ2_A"
$PN"152"115;
"DQ1_A"
$PN"9"114;
"DQ0_A"
$PN"7"113;
"DQ31_B"
$PN"287"112;
"DQ30_B"
$PN"285"74;
"DQ29_B"
$PN"142"111;
"DQ28_B"
$PN"140"110;
"DQ27_B"
$PN"280"109;
"DQ26_B"
$PN"278"108;
"DQ25_B"
$PN"135"107;
"DQ24_B"
$PN"133"106;
"DQ23_B"
$PN"276"105;
"DQ22_B"
$PN"274"70;
"DQ21_B"
$PN"131"104;
"DQ20_B"
$PN"129"103;
"DQ19_B"
$PN"269"102;
"DQ18_B"
$PN"267"101;
"DQ17_B"
$PN"124"100;
"DQ16_B"
$PN"122"99;
"DQ15_B"
$PN"265"98;
"DQ14_B"
$PN"263"97;
"DQ13_B"
$PN"120"96;
"DQ12_B"
$PN"118"95;
"DQ11_B"
$PN"258"94;
"DQ10_B"
$PN"256"93;
"DQ9_B"
$PN"113"92;
"DQ8_B"
$PN"111"91;
"DQ7_B"
$PN"254"90;
"DQ6_B"
$PN"252"89;
"DQ5_B"
$PN"109"88;
"DQ4_B"
$PN"107"87;
"DQ3_B"
$PN"247"86;
"DQ2_B"
$PN"245"85;
"DQ1_B"
$PN"102"84;
"DQ0_B"
$PN"100"83;
"HSA"
$PN"148"21;
"HSCL"
$PN"4"20;
"HSDA"
$PN"5"22;
"LBD||RSP_A_N"
$PN"86"82;
"LBS||RSP_B_N"
$PN"87"81;
"PAR_A"
$PN"74"80;
"PAR_B"
$PN"227"79;
"PWR_GOOD||FAIL_N"
$PN"147"69;
"RESET_N \B"
$PN"207"24;
"RFU6"
$PN"232"28;
"RFU5"
$PN"231"27;
"RFU4"
$PN"220"26;
"RFU3"
$PN"150"78;
"RFU2"
$PN"149"77;
"RFU1"
$PN"144"76;
"RFU0"
$PN"2"75;
"VIN_MGMT"
$PN"3"2;
%"TAP"
"1","(2525,2475)","0","standard","I130";
;
CDS_LIB"standard"
BODY_TYPE"PLUMBING"
HDL_TAP"TRUE";
"B \NAC \NWC"16;
"S \NAC"
BN"3"65;
%"TAP"
"1","(2525,2375)","0","standard","I131";
;
CDS_LIB"standard"
BODY_TYPE"PLUMBING"
HDL_TAP"TRUE";
"B \NAC \NWC"16;
"S \NAC"
BN"2"66;
%"TAP"
"1","(2525,2575)","0","standard","I132";
;
CDS_LIB"standard"
BODY_TYPE"PLUMBING"
HDL_TAP"TRUE";
"B \NAC \NWC"16;
"S \NAC"
BN"4"64;
%"TAP"
"1","(2525,2675)","0","standard","I133";
;
CDS_LIB"standard"
BODY_TYPE"PLUMBING"
HDL_TAP"TRUE";
"B \NAC \NWC"16;
"S \NAC"
BN"5"63;
%"TAP"
"1","(2525,2775)","0","standard","I134";
;
CDS_LIB"standard"
BODY_TYPE"PLUMBING"
HDL_TAP"TRUE";
"B \NAC \NWC"16;
"S \NAC"
BN"6"62;
%"TAP"
"1","(2525,2975)","0","standard","I135";
;
CDS_LIB"standard"
BODY_TYPE"PLUMBING"
HDL_TAP"TRUE";
"B \NAC \NWC"16;
"S \NAC"
BN"8"60;
%"TAP"
"1","(2525,2875)","0","standard","I136";
;
CDS_LIB"standard"
BODY_TYPE"PLUMBING"
HDL_TAP"TRUE";
"B \NAC \NWC"16;
"S \NAC"
BN"7"61;
%"TAP"
"1","(2525,3225)","0","standard","I137";
;
CDS_LIB"standard"
BODY_TYPE"PLUMBING"
HDL_TAP"TRUE";
"B \NAC \NWC"17;
"S \NAC"
BN"0"58;
%"TAP"
"1","(2525,3075)","0","standard","I138";
;
CDS_LIB"standard"
BODY_TYPE"PLUMBING"
HDL_TAP"TRUE";
"B \NAC \NWC"16;
"S \NAC"
BN"9"59;
%"TAP"
"1","(2525,3325)","0","standard","I139";
;
CDS_LIB"standard"
BODY_TYPE"PLUMBING"
HDL_TAP"TRUE";
"B \NAC \NWC"17;
"S \NAC"
BN"1"57;
%"TAP"
"1","(-1875,1925)","2","standard","I14";
;
CDS_LIB"standard"
BODY_TYPE"PLUMBING"
HDL_TAP"TRUE";
"B \NAC \NWC"12;
"S \NAC"
BN"0"148;
%"TAP"
"1","(2525,3425)","0","standard","I140";
;
CDS_LIB"standard"
BODY_TYPE"PLUMBING"
HDL_TAP"TRUE";
"B \NAC \NWC"17;
"S \NAC"
BN"2"56;
%"TAP"
"1","(2525,3525)","0","standard","I141";
;
CDS_LIB"standard"
BODY_TYPE"PLUMBING"
HDL_TAP"TRUE";
"B \NAC \NWC"17;
"S \NAC"
BN"3"55;
%"TAP"
"1","(2525,3625)","0","standard","I142";
;
CDS_LIB"standard"
BODY_TYPE"PLUMBING"
HDL_TAP"TRUE";
"B \NAC \NWC"17;
"S \NAC"
BN"4"54;
%"TAP"
"1","(2525,3725)","0","standard","I143";
;
CDS_LIB"standard"
BODY_TYPE"PLUMBING"
HDL_TAP"TRUE";
"B \NAC \NWC"17;
"S \NAC"
BN"5"53;
%"TAP"
"1","(2525,3825)","0","standard","I144";
;
CDS_LIB"standard"
BODY_TYPE"PLUMBING"
HDL_TAP"TRUE";
"B \NAC \NWC"17;
"S \NAC"
BN"6"52;
%"TAP"
"1","(2525,3925)","0","standard","I145";
;
CDS_LIB"standard"
BODY_TYPE"PLUMBING"
HDL_TAP"TRUE";
"B \NAC \NWC"17;
"S \NAC"
BN"7"51;
%"Q_CAP"
"1","(3125,250)","0","pure_quanta","I146";
;
PART_NUMBER"CH6103KEA00"
TOLERANCE"10%"
VOLTAGE"16V"
VALUE"10UF"
PACK_TYPE"C0805"
MATERIAL"X6S"
$LOCATION"C31"
CDS_LIB"pure_quanta"
CDS_LOCATION"C31"
$SEC"1"
CDS_SEC"1";
"B"
$PN"2"7;
"A"
$PN"1"4;
%"UNIVERSAL_GND"
"1","(4200,425)","0","logical_power","I147";
;
CDS_LIB"logical_power"
HDL_POWER"GND";
"A"6;
%"SCONN288_ADR50017P087CC"
"3","(5050,2500)","0","pure_quanta","I148";
;
PART_NUMBER"DFHST8FS460"
MATERIAL"IO"
PART_TYPE"SMLF"
VALUE"SCONN288_ADR50017-P087CC"
$LOCATION"J10"
NEEDS_NO_SIZE"TRUE"
CDS_LMAN_SYM_OUTLINE"-450,1775,450,-1775"
CDS_LIB"pure_quanta"
CDS_LOCATION"J10"
$SEC"3"
CDS_SEC"3";
"G3"
$PN"G3"5;
"G2"
$PN"G2"5;
"G1"
$PN"G1"5;
"VSS62"
$PN"141"5;
"VSS61"
$PN"139"5;
"VSS60"
$PN"136"5;
"VSS58"
$PN"132"5;
"VSS104"
$PN"240"6;
"VSS102"
$PN"235"6;
"VSS100"
$PN"230"6;
"VIN_BULK2"
$PN"146"3;
"VIN_BULK1"
$PN"145"3;
"VIN_BULK0"
$PN"1"3;
"VSS126"
$PN"288"6;
"VSS125"
$PN"286"6;
"VSS124"
$PN"284"6;
"VSS123"
$PN"281"6;
"VSS122"
$PN"279"6;
"VSS121"
$PN"277"6;
"VSS120"
$PN"275"6;
"VSS119"
$PN"273"6;
"VSS118"
$PN"270"6;
"VSS117"
$PN"268"6;
"VSS116"
$PN"266"6;
"VSS115"
$PN"264"6;
"VSS114"
$PN"262"6;
"VSS113"
$PN"259"6;
"VSS112"
$PN"257"6;
"VSS111"
$PN"255"6;
"VSS110"
$PN"253"6;
"VSS109"
$PN"251"6;
"VSS108"
$PN"248"6;
"VSS107"
$PN"246"6;
"VSS106"
$PN"244"6;
"VSS105"
$PN"242"6;
"VSS103"
$PN"237"6;
"VSS101"
$PN"233"6;
"VSS99"
$PN"228"6;
"VSS98"
$PN"226"6;
"VSS97"
$PN"224"6;
"VSS96"
$PN"222"6;
"VSS95"
$PN"219"6;
"VSS94"
$PN"216"6;
"VSS93"
$PN"214"6;
"VSS92"
$PN"212"6;
"VSS91"
$PN"210"6;
"VSS90"
$PN"208"6;
"VSS89"
$PN"206"6;
"VSS88"
$PN"204"6;
"VSS87"
$PN"202"6;
"VSS86"
$PN"199"6;
"VSS85"
$PN"197"6;
"VSS84"
$PN"195"6;
"VSS83"
$PN"193"6;
"VSS82"
$PN"191"6;
"VSS81"
$PN"188"6;
"VSS80"
$PN"186"6;
"VSS79"
$PN"184"6;
"VSS78"
$PN"182"6;
"VSS77"
$PN"180"6;
"VSS76"
$PN"177"6;
"VSS75"
$PN"175"6;
"VSS74"
$PN"173"6;
"VSS73"
$PN"171"6;
"VSS72"
$PN"169"6;
"VSS71"
$PN"166"6;
"VSS70"
$PN"164"6;
"VSS69"
$PN"162"6;
"VSS68"
$PN"160"6;
"VSS67"
$PN"158"6;
"VSS66"
$PN"155"6;
"VSS65"
$PN"153"6;
"VSS64"
$PN"151"6;
"VSS63"
$PN"143"5;
"VSS59"
$PN"134"5;
"VSS57"
$PN"130"5;
"VSS56"
$PN"128"5;
"VSS55"
$PN"125"5;
"VSS54"
$PN"123"5;
"VSS53"
$PN"121"5;
"VSS52"
$PN"119"5;
"VSS51"
$PN"117"5;
"VSS50"
$PN"114"5;
"VSS49"
$PN"112"5;
"VSS48"
$PN"110"5;
"VSS47"
$PN"108"5;
"VSS46"
$PN"106"5;
"VSS45"
$PN"103"5;
"VSS44"
$PN"101"5;
"VSS43"
$PN"99"5;
"VSS42"
$PN"97"5;
"VSS41"
$PN"95"5;
"VSS40"
$PN"92"5;
"VSS39"
$PN"90"5;
"VSS38"
$PN"88"5;
"VSS37"
$PN"85"5;
"VSS36"
$PN"83"5;
"VSS35"
$PN"81"5;
"VSS34"
$PN"79"5;
"VSS33"
$PN"77"5;
"VSS32"
$PN"75"5;
"VSS31"
$PN"73"5;
"VSS30"
$PN"71"5;
"VSS29"
$PN"69"5;
"VSS28"
$PN"67"5;
"VSS27"
$PN"65"5;
"VSS26"
$PN"63"5;
"VSS25"
$PN"61"5;
"VSS24"
$PN"59"5;
"VSS23"
$PN"57"5;
"VSS22"
$PN"54"5;
"VSS21"
$PN"52"5;
"VSS20"
$PN"50"5;
"VSS19"
$PN"48"5;
"VSS18"
$PN"46"5;
"VSS17"
$PN"43"5;
"VSS16"
$PN"41"5;
"VSS15"
$PN"39"5;
"VSS14"
$PN"37"5;
"VSS13"
$PN"35"5;
"VSS12"
$PN"32"5;
"VSS11"
$PN"30"5;
"VSS10"
$PN"28"5;
"VSS9"
$PN"26"5;
"VSS8"
$PN"24"5;
"VSS7"
$PN"21"5;
"VSS6"
$PN"19"5;
"VSS5"
$PN"17"5;
"VSS4"
$PN"15"5;
"VSS3"
$PN"13"5;
"VSS2"
$PN"10"5;
"VSS1"
$PN"8"5;
"VSS0"
$PN"6"5;
%"TAP"
"1","(2700,2225)","0","standard","I149";
;
CDS_LIB"standard"
BODY_TYPE"PLUMBING"
HDL_TAP"TRUE";
"B \NAC \NWC"18;
"S \NAC"
BN"1"47;
%"TAP"
"1","(2700,2125)","0","standard","I150";
;
CDS_LIB"standard"
BODY_TYPE"PLUMBING"
HDL_TAP"TRUE";
"B \NAC \NWC"18;
"S \NAC"
BN"0"48;
%"TAP"
"1","(2700,2325)","0","standard","I151";
;
CDS_LIB"standard"
BODY_TYPE"PLUMBING"
HDL_TAP"TRUE";
"B \NAC \NWC"18;
"S \NAC"
BN"2"45;
%"TAP"
"1","(2700,2425)","0","standard","I152";
;
CDS_LIB"standard"
BODY_TYPE"PLUMBING"
HDL_TAP"TRUE";
"B \NAC \NWC"18;
"S \NAC"
BN"3"46;
%"TAP"
"1","(2700,2525)","0","standard","I153";
;
CDS_LIB"standard"
BODY_TYPE"PLUMBING"
HDL_TAP"TRUE";
"B \NAC \NWC"18;
"S \NAC"
BN"4"29;
%"TAP"
"1","(2700,2625)","0","standard","I154";
;
CDS_LIB"standard"
BODY_TYPE"PLUMBING"
HDL_TAP"TRUE";
"B \NAC \NWC"18;
"S \NAC"
BN"5"44;
%"TAP"
"1","(2700,2725)","0","standard","I155";
;
CDS_LIB"standard"
BODY_TYPE"PLUMBING"
HDL_TAP"TRUE";
"B \NAC \NWC"18;
"S \NAC"
BN"6"43;
%"TAP"
"1","(2700,2825)","0","standard","I156";
;
CDS_LIB"standard"
BODY_TYPE"PLUMBING"
HDL_TAP"TRUE";
"B \NAC \NWC"18;
"S \NAC"
BN"7"41;
%"TAP"
"1","(2700,2925)","0","standard","I157";
;
CDS_LIB"standard"
BODY_TYPE"PLUMBING"
HDL_TAP"TRUE";
"B \NAC \NWC"18;
"S \NAC"
BN"8"42;
%"TAP"
"1","(2700,3025)","0","standard","I158";
;
CDS_LIB"standard"
BODY_TYPE"PLUMBING"
HDL_TAP"TRUE";
"B \NAC \NWC"18;
"S \NAC"
BN"9"40;
%"TAP"
"1","(2700,3175)","0","standard","I159";
;
CDS_LIB"standard"
BODY_TYPE"PLUMBING"
HDL_TAP"TRUE";
"B \NAC \NWC"19;
"S \NAC"
BN"0"39;
%"TAP"
"1","(2700,3375)","0","standard","I160";
;
CDS_LIB"standard"
BODY_TYPE"PLUMBING"
HDL_TAP"TRUE";
"B \NAC \NWC"19;
"S \NAC"
BN"2"37;
%"TAP"
"1","(2700,3275)","0","standard","I161";
;
CDS_LIB"standard"
BODY_TYPE"PLUMBING"
HDL_TAP"TRUE";
"B \NAC \NWC"19;
"S \NAC"
BN"1"38;
%"TAP"
"1","(2700,3475)","0","standard","I162";
;
CDS_LIB"standard"
BODY_TYPE"PLUMBING"
HDL_TAP"TRUE";
"B \NAC \NWC"19;
"S \NAC"
BN"3"35;
%"TAP"
"1","(2700,3575)","0","standard","I163";
;
CDS_LIB"standard"
BODY_TYPE"PLUMBING"
HDL_TAP"TRUE";
"B \NAC \NWC"19;
"S \NAC"
BN"4"36;
%"TAP"
"1","(2700,3675)","0","standard","I164";
;
CDS_LIB"standard"
BODY_TYPE"PLUMBING"
HDL_TAP"TRUE";
"B \NAC \NWC"19;
"S \NAC"
BN"5"34;
%"TAP"
"1","(2700,3875)","0","standard","I165";
;
CDS_LIB"standard"
BODY_TYPE"PLUMBING"
HDL_TAP"TRUE";
"B \NAC \NWC"19;
"S \NAC"
BN"7"32;
%"TAP"
"1","(2700,3775)","0","standard","I166";
;
CDS_LIB"standard"
BODY_TYPE"PLUMBING"
HDL_TAP"TRUE";
"B \NAC \NWC"19;
"S \NAC"
BN"6"33;
%"TAP"
"1","(2700,3975)","0","standard","I167";
;
CDS_LIB"standard"
BODY_TYPE"PLUMBING"
HDL_TAP"TRUE";
"B \NAC \NWC"19;
"S \NAC"
BN"8"31;
%"TAP"
"1","(2525,4125)","0","standard","I171";
;
CDS_LIB"standard"
BODY_TYPE"PLUMBING"
HDL_TAP"TRUE";
"B \NAC \NWC"17;
"S \NAC"
BN"9"49;
%"TAP"
"1","(2525,4025)","0","standard","I172";
;
CDS_LIB"standard"
BODY_TYPE"PLUMBING"
HDL_TAP"TRUE";
"B \NAC \NWC"17;
"S \NAC"
BN"8"50;
%"TAP"
"1","(2700,4075)","0","standard","I173";
;
CDS_LIB"standard"
BODY_TYPE"PLUMBING"
HDL_TAP"TRUE";
"B \NAC \NWC"19;
"S \NAC"
BN"9"30;
%"VCC_CORE"
"1","(4200,4675)","0","logical_power","I176";
;
HDL_POWER"P12V_S3_AUX_CPU0_NVDIMM"
CDS_LIB"logical_power";
"A"3;
%"UNIVERSAL_GND"
"1","(5900,425)","0","logical_power","I177";
;
CDS_LIB"logical_power"
HDL_POWER"GND";
"A"5;
%"SCONN288_ADR50017P087CC"
"2","(1625,3125)","0","pure_quanta","I178";
;
PART_NUMBER"DFHST8FS460"
MATERIAL"IO"
PART_TYPE"SMLF"
VALUE"SCONN288_ADR50017-P087CC"
LOCATION"J10"
NEEDS_NO_SIZE"TRUE"
CDS_LMAN_SYM_OUTLINE"-600,1150,600,-1150"
CDS_LIB"pure_quanta"
$SEC"2"
CDS_SEC"2";
"DQS7_A_C||TDQS7_A_C \B"
$PN"178"32;
"DQS6_A_T||TDQS6_A_T"
$PN"168"52;
"DQS8_B_T||TDQS8_B_T"
$PN"283"60;
"DQS8_B_C||TDQS8_B_C \B"
$PN"282"42;
"DQS7_B_T||TDQS7_B_T"
$PN"272"61;
"DQS0_A_C \B"
$PN"12"39;
"DQS0_A_T"
$PN"11"58;
"DQS0_B_C \B"
$PN"105"48;
"DQS0_B_T"
$PN"104"68;
"DQS1_A_C \B"
$PN"23"38;
"DQS1_A_T"
$PN"22"57;
"DQS1_B_C \B"
$PN"116"47;
"DQS1_B_T"
$PN"115"67;
"DQS2_A_C \B"
$PN"34"37;
"DQS2_A_T"
$PN"33"56;
"DQS2_B_C \B"
$PN"127"45;
"DQS2_B_T"
$PN"126"66;
"DQS3_A_C \B"
$PN"45"35;
"DQS3_A_T"
$PN"44"55;
"DQS3_B_C \B"
$PN"138"46;
"DQS3_B_T"
$PN"137"65;
"DQS4_A_C \B"
$PN"56"36;
"DQS4_A_T"
$PN"55"54;
"DQS4_B_C \B"
$PN"238"29;
"DQS4_B_T"
$PN"239"64;
"DQS5_A_C||TDQS5_A_C||DQS5_A_T||TDQS5_A_T \B"
$PN"156"34;
"DQS5_A_T||TDQS5_A_T"
$PN"157"53;
"DQS5_B_C||TDQS5_B_C \B"
$PN"249"44;
"DQS5_B_T||TDQS5_B_T"
$PN"250"63;
"DQS6_A_C||TDQS6_A_C||DQS6_A_T||TDQS6_A_T \B"
$PN"167"33;
"DQS6_B_C||TDQS6_B_C \B"
$PN"260"43;
"DQS6_B_T||TDQS6_B_T"
$PN"261"62;
"DQS7_A_T||TDQS7_A_T"
$PN"179"51;
"DQS7_B_C||TDQS7_B_C \B"
$PN"271"41;
"DQS8_A_C||TDQS8_A_C \B"
$PN"189"31;
"DQS8_A_T||TDQS8_A_T"
$PN"190"50;
"DQS9_A_C||TDQS9_A_C \B"
$PN"200"30;
"DQS9_A_T||TDQS9_A_T"
$PN"201"49;
"DQS9_B_C||TDQS9_B_C \B"
$PN"94"40;
"DQS9_B_T||TDQS9_B_T||DBI4_B_N"
$PN"93"59;
%"Q_RES"
"1","(-2825,1400)","0","pure_quanta","I179";
;
PART_NUMBER"CS04992FB07"
VALUE"49.9"
MATERIAL"CHIP"
$LOCATION"R3884"
CDS_LIB"pure_quanta"
PACK_TYPE"0402LF"
WATTAGE"1/16W"
TOLERANCE"1%"
CDS_LOCATION"R3884"
$SEC"1"
CDS_SEC"1";
"B"
$PN"2"25;
"A"
$PN"1"20;
%"Q_RES"
"2","(-1650,-25)","0","pure_quanta","I2";
;
PART_NUMBER"CS31542FB02"
WATTAGE"1/16W"
MATERIAL"CHIP"
TOLERANCE"1%"
VALUE"15.4K"
PACK_TYPE"0402LF"
$LOCATION"R35"
CDS_LIB"pure_quanta"
CDS_LOCATION"R35"
$SEC"1"
CDS_SEC"1";
"A"
$PN"1"178;
"B"
$PN"2"9;
%"TAP"
"1","(-1875,1975)","2","standard","I26";
;
CDS_LIB"standard"
BODY_TYPE"PLUMBING"
HDL_TAP"TRUE";
"B \NAC \NWC"12;
"S \NAC"
BN"1"149;
%"TAP"
"1","(-1875,2025)","2","standard","I27";
;
CDS_LIB"standard"
BODY_TYPE"PLUMBING"
HDL_TAP"TRUE";
"B \NAC \NWC"12;
"S \NAC"
BN"2"150;
%"TAP"
"1","(-1875,2075)","2","standard","I28";
;
CDS_LIB"standard"
BODY_TYPE"PLUMBING"
HDL_TAP"TRUE";
"B \NAC \NWC"12;
"S \NAC"
BN"3"151;
%"TAP"
"1","(-1875,2125)","2","standard","I29";
;
CDS_LIB"standard"
BODY_TYPE"PLUMBING"
HDL_TAP"TRUE";
"B \NAC \NWC"12;
"S \NAC"
BN"4"152;
%"TAP"
"1","(-1875,2175)","2","standard","I30";
;
CDS_LIB"standard"
BODY_TYPE"PLUMBING"
HDL_TAP"TRUE";
"B \NAC \NWC"12;
"S \NAC"
BN"5"153;
%"TAP"
"1","(-1875,2225)","2","standard","I31";
;
CDS_LIB"standard"
BODY_TYPE"PLUMBING"
HDL_TAP"TRUE";
"B \NAC \NWC"12;
"S \NAC"
BN"6"154;
%"TAP"
"1","(-1875,2275)","2","standard","I32";
;
CDS_LIB"standard"
BODY_TYPE"PLUMBING"
HDL_TAP"TRUE";
"B \NAC \NWC"12;
"S \NAC"
BN"7"173;
%"TAP"
"1","(-1875,2425)","2","standard","I33";
;
CDS_LIB"standard"
BODY_TYPE"PLUMBING"
HDL_TAP"TRUE";
"B \NAC \NWC"11;
"S \NAC"
BN"1"174;
%"TAP"
"1","(-1875,2375)","2","standard","I34";
;
CDS_LIB"standard"
BODY_TYPE"PLUMBING"
HDL_TAP"TRUE";
"B \NAC \NWC"11;
"S \NAC"
BN"0"71;
%"TAP"
"1","(-1875,2475)","2","standard","I35";
;
CDS_LIB"standard"
BODY_TYPE"PLUMBING"
HDL_TAP"TRUE";
"B \NAC \NWC"11;
"S \NAC"
BN"2"155;
%"TAP"
"1","(-1875,2525)","2","standard","I36";
;
CDS_LIB"standard"
BODY_TYPE"PLUMBING"
HDL_TAP"TRUE";
"B \NAC \NWC"11;
"S \NAC"
BN"3"156;
%"TAP"
"1","(-1875,2575)","2","standard","I37";
;
CDS_LIB"standard"
BODY_TYPE"PLUMBING"
HDL_TAP"TRUE";
"B \NAC \NWC"11;
"S \NAC"
BN"4"175;
%"TAP"
"1","(-1875,2675)","2","standard","I38";
;
CDS_LIB"standard"
BODY_TYPE"PLUMBING"
HDL_TAP"TRUE";
"B \NAC \NWC"11;
"S \NAC"
BN"6"158;
%"TAP"
"1","(-1875,2625)","2","standard","I39";
;
CDS_LIB"standard"
BODY_TYPE"PLUMBING"
HDL_TAP"TRUE";
"B \NAC \NWC"11;
"S \NAC"
BN"5"157;
%"TAP"
"1","(-1875,2725)","2","standard","I40";
;
CDS_LIB"standard"
BODY_TYPE"PLUMBING"
HDL_TAP"TRUE";
"B \NAC \NWC"11;
"S \NAC"
BN"7"176;
%"TAP"
"1","(-1875,3425)","2","standard","I41";
;
CDS_LIB"standard"
BODY_TYPE"PLUMBING"
HDL_TAP"TRUE";
"B \NAC \NWC"14;
"S \NAC"
BN"0"171;
%"TAP"
"1","(-1875,3475)","2","standard","I42";
;
CDS_LIB"standard"
BODY_TYPE"PLUMBING"
HDL_TAP"TRUE";
"B \NAC \NWC"14;
"S \NAC"
BN"1"169;
%"TAP"
"1","(-1875,3525)","2","standard","I43";
;
CDS_LIB"standard"
BODY_TYPE"PLUMBING"
HDL_TAP"TRUE";
"B \NAC \NWC"14;
"S \NAC"
BN"2"167;
%"TAP"
"1","(-1875,3575)","2","standard","I44";
;
CDS_LIB"standard"
BODY_TYPE"PLUMBING"
HDL_TAP"TRUE";
"B \NAC \NWC"14;
"S \NAC"
BN"3"165;
%"TAP"
"1","(-1875,3625)","2","standard","I45";
;
CDS_LIB"standard"
BODY_TYPE"PLUMBING"
HDL_TAP"TRUE";
"B \NAC \NWC"14;
"S \NAC"
BN"4"163;
%"TAP"
"1","(-1875,3725)","2","standard","I46";
;
CDS_LIB"standard"
BODY_TYPE"PLUMBING"
HDL_TAP"TRUE";
"B \NAC \NWC"14;
"S \NAC"
BN"6"159;
%"TAP"
"1","(-1875,3675)","2","standard","I47";
;
CDS_LIB"standard"
BODY_TYPE"PLUMBING"
HDL_TAP"TRUE";
"B \NAC \NWC"14;
"S \NAC"
BN"5"161;
%"TAP"
"1","(-1875,3825)","2","standard","I48";
;
CDS_LIB"standard"
BODY_TYPE"PLUMBING"
HDL_TAP"TRUE";
"B \NAC \NWC"13;
"S \NAC"
BN"0"172;
%"TAP"
"1","(-1875,3875)","2","standard","I49";
;
CDS_LIB"standard"
BODY_TYPE"PLUMBING"
HDL_TAP"TRUE";
"B \NAC \NWC"13;
"S \NAC"
BN"1"170;
%"TAP"
"1","(-1875,3925)","2","standard","I50";
;
CDS_LIB"standard"
BODY_TYPE"PLUMBING"
HDL_TAP"TRUE";
"B \NAC \NWC"13;
"S \NAC"
BN"2"168;
%"TAP"
"1","(-1875,3975)","2","standard","I51";
;
CDS_LIB"standard"
BODY_TYPE"PLUMBING"
HDL_TAP"TRUE";
"B \NAC \NWC"13;
"S \NAC"
BN"3"166;
%"TAP"
"1","(-225,925)","0","standard","I52";
;
CDS_LIB"standard"
BODY_TYPE"PLUMBING"
HDL_TAP"TRUE";
"B \NAC \NWC"15;
"S \NAC"
BN"0"83;
%"TAP"
"1","(-225,975)","0","standard","I53";
;
CDS_LIB"standard"
BODY_TYPE"PLUMBING"
HDL_TAP"TRUE";
"B \NAC \NWC"15;
"S \NAC"
BN"1"84;
%"TAP"
"1","(-225,1075)","0","standard","I54";
;
CDS_LIB"standard"
BODY_TYPE"PLUMBING"
HDL_TAP"TRUE";
"B \NAC \NWC"15;
"S \NAC"
BN"3"86;
%"TAP"
"1","(-225,1025)","0","standard","I55";
;
CDS_LIB"standard"
BODY_TYPE"PLUMBING"
HDL_TAP"TRUE";
"B \NAC \NWC"15;
"S \NAC"
BN"2"85;
%"TAP"
"1","(-225,1125)","0","standard","I56";
;
CDS_LIB"standard"
BODY_TYPE"PLUMBING"
HDL_TAP"TRUE";
"B \NAC \NWC"15;
"S \NAC"
BN"4"87;
%"TAP"
"1","(-225,1175)","0","standard","I57";
;
CDS_LIB"standard"
BODY_TYPE"PLUMBING"
HDL_TAP"TRUE";
"B \NAC \NWC"15;
"S \NAC"
BN"5"88;
%"TAP"
"1","(-225,1225)","0","standard","I58";
;
CDS_LIB"standard"
BODY_TYPE"PLUMBING"
HDL_TAP"TRUE";
"B \NAC \NWC"15;
"S \NAC"
BN"6"89;
%"TAP"
"1","(-225,1325)","0","standard","I59";
;
CDS_LIB"standard"
BODY_TYPE"PLUMBING"
HDL_TAP"TRUE";
"B \NAC \NWC"15;
"S \NAC"
BN"8"91;
%"TAP"
"1","(-225,1275)","0","standard","I60";
;
CDS_LIB"standard"
BODY_TYPE"PLUMBING"
HDL_TAP"TRUE";
"B \NAC \NWC"15;
"S \NAC"
BN"7"90;
%"TAP"
"1","(-225,1375)","0","standard","I61";
;
CDS_LIB"standard"
BODY_TYPE"PLUMBING"
HDL_TAP"TRUE";
"B \NAC \NWC"15;
"S \NAC"
BN"9"92;
%"TAP"
"1","(-225,1425)","0","standard","I62";
;
CDS_LIB"standard"
BODY_TYPE"PLUMBING"
HDL_TAP"TRUE";
"B \NAC \NWC"15;
"S \NAC"
BN"10"93;
%"TAP"
"1","(-225,1475)","0","standard","I63";
;
CDS_LIB"standard"
BODY_TYPE"PLUMBING"
HDL_TAP"TRUE";
"B \NAC \NWC"15;
"S \NAC"
BN"11"94;
%"TAP"
"1","(-225,1525)","0","standard","I64";
;
CDS_LIB"standard"
BODY_TYPE"PLUMBING"
HDL_TAP"TRUE";
"B \NAC \NWC"15;
"S \NAC"
BN"12"95;
%"TAP"
"1","(-225,1575)","0","standard","I65";
;
CDS_LIB"standard"
BODY_TYPE"PLUMBING"
HDL_TAP"TRUE";
"B \NAC \NWC"15;
"S \NAC"
BN"13"96;
%"TAP"
"1","(-225,1625)","0","standard","I66";
;
CDS_LIB"standard"
BODY_TYPE"PLUMBING"
HDL_TAP"TRUE";
"B \NAC \NWC"15;
"S \NAC"
BN"14"97;
%"TAP"
"1","(-225,1675)","0","standard","I67";
;
CDS_LIB"standard"
BODY_TYPE"PLUMBING"
HDL_TAP"TRUE";
"B \NAC \NWC"15;
"S \NAC"
BN"15"98;
%"TAP"
"1","(-225,1775)","0","standard","I68";
;
CDS_LIB"standard"
BODY_TYPE"PLUMBING"
HDL_TAP"TRUE";
"B \NAC \NWC"15;
"S \NAC"
BN"17"100;
%"TAP"
"1","(-225,1725)","0","standard","I69";
;
CDS_LIB"standard"
BODY_TYPE"PLUMBING"
HDL_TAP"TRUE";
"B \NAC \NWC"15;
"S \NAC"
BN"16"99;
%"TAP"
"1","(-225,1825)","0","standard","I70";
;
CDS_LIB"standard"
BODY_TYPE"PLUMBING"
HDL_TAP"TRUE";
"B \NAC \NWC"15;
"S \NAC"
BN"18"101;
%"TAP"
"1","(-225,1875)","0","standard","I71";
;
CDS_LIB"standard"
BODY_TYPE"PLUMBING"
HDL_TAP"TRUE";
"B \NAC \NWC"15;
"S \NAC"
BN"19"102;
%"TAP"
"1","(-225,1925)","0","standard","I72";
;
CDS_LIB"standard"
BODY_TYPE"PLUMBING"
HDL_TAP"TRUE";
"B \NAC \NWC"15;
"S \NAC"
BN"20"103;
%"TAP"
"1","(-225,1975)","0","standard","I73";
;
CDS_LIB"standard"
BODY_TYPE"PLUMBING"
HDL_TAP"TRUE";
"B \NAC \NWC"15;
"S \NAC"
BN"21"104;
%"TAP"
"1","(-225,2025)","0","standard","I74";
;
CDS_LIB"standard"
BODY_TYPE"PLUMBING"
HDL_TAP"TRUE";
"B \NAC \NWC"15;
"S \NAC"
BN"22"70;
%"TAP"
"1","(-225,2075)","0","standard","I75";
;
CDS_LIB"standard"
BODY_TYPE"PLUMBING"
HDL_TAP"TRUE";
"B \NAC \NWC"15;
"S \NAC"
BN"23"105;
%"TAP"
"1","(-225,2125)","0","standard","I76";
;
CDS_LIB"standard"
BODY_TYPE"PLUMBING"
HDL_TAP"TRUE";
"B \NAC \NWC"15;
"S \NAC"
BN"24"106;
%"TAP"
"1","(-225,2225)","0","standard","I77";
;
CDS_LIB"standard"
BODY_TYPE"PLUMBING"
HDL_TAP"TRUE";
"B \NAC \NWC"15;
"S \NAC"
BN"26"108;
%"TAP"
"1","(-225,2175)","0","standard","I78";
;
CDS_LIB"standard"
BODY_TYPE"PLUMBING"
HDL_TAP"TRUE";
"B \NAC \NWC"15;
"S \NAC"
BN"25"107;
%"TAP"
"1","(-225,2275)","0","standard","I79";
;
CDS_LIB"standard"
BODY_TYPE"PLUMBING"
HDL_TAP"TRUE";
"B \NAC \NWC"15;
"S \NAC"
BN"27"109;
%"TAP"
"1","(-225,2325)","0","standard","I80";
;
CDS_LIB"standard"
BODY_TYPE"PLUMBING"
HDL_TAP"TRUE";
"B \NAC \NWC"15;
"S \NAC"
BN"28"110;
%"TAP"
"1","(-225,2375)","0","standard","I81";
;
CDS_LIB"standard"
BODY_TYPE"PLUMBING"
HDL_TAP"TRUE";
"B \NAC \NWC"15;
"S \NAC"
BN"29"111;
%"TAP"
"1","(-225,2425)","0","standard","I82";
;
CDS_LIB"standard"
BODY_TYPE"PLUMBING"
HDL_TAP"TRUE";
"B \NAC \NWC"15;
"S \NAC"
BN"30"74;
%"TAP"
"1","(-225,2475)","0","standard","I83";
;
CDS_LIB"standard"
BODY_TYPE"PLUMBING"
HDL_TAP"TRUE";
"B \NAC \NWC"15;
"S \NAC"
BN"31"112;
%"TAP"
"1","(-225,2575)","0","standard","I84";
;
CDS_LIB"standard"
BODY_TYPE"PLUMBING"
HDL_TAP"TRUE";
"B \NAC \NWC"10;
"S \NAC"
BN"0"113;
%"TAP"
"1","(-225,2675)","0","standard","I85";
;
CDS_LIB"standard"
BODY_TYPE"PLUMBING"
HDL_TAP"TRUE";
"B \NAC \NWC"10;
"S \NAC"
BN"2"115;
%"TAP"
"1","(-225,2625)","0","standard","I86";
;
CDS_LIB"standard"
BODY_TYPE"PLUMBING"
HDL_TAP"TRUE";
"B \NAC \NWC"10;
"S \NAC"
BN"1"114;
%"TAP"
"1","(-225,2725)","0","standard","I87";
;
CDS_LIB"standard"
BODY_TYPE"PLUMBING"
HDL_TAP"TRUE";
"B \NAC \NWC"10;
"S \NAC"
BN"3"116;
%"TAP"
"1","(-225,2775)","0","standard","I88";
;
CDS_LIB"standard"
BODY_TYPE"PLUMBING"
HDL_TAP"TRUE";
"B \NAC \NWC"10;
"S \NAC"
BN"4"73;
%"TAP"
"1","(-225,2825)","0","standard","I89";
;
CDS_LIB"standard"
BODY_TYPE"PLUMBING"
HDL_TAP"TRUE";
"B \NAC \NWC"10;
"S \NAC"
BN"5"117;
%"TAP"
"1","(-225,2925)","0","standard","I90";
;
CDS_LIB"standard"
BODY_TYPE"PLUMBING"
HDL_TAP"TRUE";
"B \NAC \NWC"10;
"S \NAC"
BN"7"119;
%"TAP"
"1","(-225,2975)","0","standard","I91";
;
CDS_LIB"standard"
BODY_TYPE"PLUMBING"
HDL_TAP"TRUE";
"B \NAC \NWC"10;
"S \NAC"
BN"8"120;
%"TAP"
"1","(-225,2875)","0","standard","I92";
;
CDS_LIB"standard"
BODY_TYPE"PLUMBING"
HDL_TAP"TRUE";
"B \NAC \NWC"10;
"S \NAC"
BN"6"118;
%"TAP"
"1","(-225,3025)","0","standard","I93";
;
CDS_LIB"standard"
BODY_TYPE"PLUMBING"
HDL_TAP"TRUE";
"B \NAC \NWC"10;
"S \NAC"
BN"9"121;
%"TAP"
"1","(-225,3075)","0","standard","I94";
;
CDS_LIB"standard"
BODY_TYPE"PLUMBING"
HDL_TAP"TRUE";
"B \NAC \NWC"10;
"S \NAC"
BN"10"122;
%"TAP"
"1","(-225,3125)","0","standard","I95";
;
CDS_LIB"standard"
BODY_TYPE"PLUMBING"
HDL_TAP"TRUE";
"B \NAC \NWC"10;
"S \NAC"
BN"11"123;
%"TAP"
"1","(-225,3175)","0","standard","I96";
;
CDS_LIB"standard"
BODY_TYPE"PLUMBING"
HDL_TAP"TRUE";
"B \NAC \NWC"10;
"S \NAC"
BN"12"124;
%"TAP"
"1","(-225,3225)","0","standard","I97";
;
CDS_LIB"standard"
BODY_TYPE"PLUMBING"
HDL_TAP"TRUE";
"B \NAC \NWC"10;
"S \NAC"
BN"13"125;
%"TAP"
"1","(-225,3275)","0","standard","I98";
;
CDS_LIB"standard"
BODY_TYPE"PLUMBING"
HDL_TAP"TRUE";
"B \NAC \NWC"10;
"S \NAC"
BN"14"126;
%"TAP"
"1","(-225,3375)","0","standard","I99";
;
CDS_LIB"standard"
BODY_TYPE"PLUMBING"
HDL_TAP"TRUE";
"B \NAC \NWC"10;
"S \NAC"
BN"16"128;
END.
